# S9S_MB_2U (Grand Teton) — schematic netlist excerpt (pin names and nets, part order shuffled) for the footprints in the layout excerpt that follows; sources: Cadence DE-HDL packaged netlist, KiCad conversion of 03242023_DA0F0TMBIJ0_F0T_Motherboard_J_brd_V01_OCP.brd

J22  SCONN288_ADR50017P087CC  SCONN288_ADR50017-P087CC IO  pkg DDR288S_1-1VXB  page 103
  VIN_BULK0  = P12V_S3_AUX_CPU1_NVDIMM
  RFU0  = TP_CHC_CPU1_DIMM2_FRU_0
  VIN_MGMT  = P3V3_AUX
  HSCL  = I3C_SPD_DDRABCD_CPU1_LVC1_SCL_5
  HSDA  = I3C_SPD_DDRABCD_CPU1_LVC1_SDA
  VSS0  = GND
  DQ0_A  = M_C_CPU1_SA_DQ<0>
  VSS1  = GND
  DQ1_A  = M_C_CPU1_SA_DQ<1>
  VSS2  = GND
  DQS0_A_T  = M_C_CPU1_SA_DQS_DP<0>
  DQS0_A_C  = M_C_CPU1_SA_DQS_DN<0>
  VSS3  = GND
  DQ4_A  = M_C_CPU1_SA_DQ<4>
  VSS4  = GND
  DQ5_A  = M_C_CPU1_SA_DQ<5>
  VSS5  = GND
  DQ8_A  = M_C_CPU1_SA_DQ<8>
  VSS6  = GND
  DQ9_A  = M_C_CPU1_SA_DQ<9>
  VSS7  = GND
  DQS1_A_T  = M_C_CPU1_SA_DQS_DP<1>
  DQS1_A_C  = M_C_CPU1_SA_DQS_DN<1>
  VSS8  = GND
  DQ12_A  = M_C_CPU1_SA_DQ<12>
  VSS9  = GND
  DQ13_A  = M_C_CPU1_SA_DQ<13>
  VSS10  = GND
  DQ16_A  = M_C_CPU1_SA_DQ<16>
  VSS11  = GND
  DQ17_A  = M_C_CPU1_SA_DQ<17>
  VSS12  = GND
  DQS2_A_T  = M_C_CPU1_SA_DQS_DP<2>
  DQS2_A_C  = M_C_CPU1_SA_DQS_DN<2>
  VSS13  = GND
  DQ20_A  = M_C_CPU1_SA_DQ<20>
  VSS14  = GND
  DQ21_A  = M_C_CPU1_SA_DQ<21>
  VSS15  = GND
  DQ24_A  = M_C_CPU1_SA_DQ<24>
  VSS16  = GND
  DQ25_A  = M_C_CPU1_SA_DQ<25>
  VSS17  = GND
  DQS3_A_T  = M_C_CPU1_SA_DQS_DP<3>
  DQS3_A_C  = M_C_CPU1_SA_DQS_DN<3>
  VSS18  = GND
  DQ28_A  = M_C_CPU1_SA_DQ<28>
  VSS19  = GND
  DQ29_A  = M_C_CPU1_SA_DQ<29>
  VSS20  = GND
  CB0_A  = M_C_CPU1_SA_CB<0>
  VSS21  = GND
  CB1_A  = M_C_CPU1_SA_CB<1>
  VSS22  = GND
  DQS4_A_T  = M_C_CPU1_SA_DQS_DP<4>
  DQS4_A_C  = M_C_CPU1_SA_DQS_DN<4>
  VSS23  = GND
  CB4_A  = M_C_CPU1_SA_CB<4>
  VSS24  = GND
  CB5_A  = M_C_CPU1_SA_CB<5>
  VSS25  = GND
  ALERT_N  = M_C_CPU1_ALERT_N
  VSS26  = GND
  CS0_A_N  = M_C_CPU1_SA_CS_N<2>
  VSS27  = GND
  CA0_A  = M_C_CPU1_SA_CA<0>
  VSS28  = GND
  CA2_A  = M_C_CPU1_SA_CA<2>
  VSS29  = GND
  CA4_A  = M_C_CPU1_SA_CA<4>
  VSS30  = GND
  CA6_A  = M_C_CPU1_SA_CA<6>
  VSS31  = GND
  PAR_A  = M_C_CPU1_SA_PAR
  VSS32  = GND
  CA0_B  = M_C_CPU1_SB_CA<0>
  VSS33  = GND
  CA2_B  = M_C_CPU1_SB_CA<2>
  VSS34  = GND
  CA4_B  = M_C_CPU1_SB_CA<4>
  VSS35  = GND
  CA6_B  = M_C_CPU1_SB_CA<6>
  VSS36  = GND
  CS0_B_N  = M_C_CPU1_SB_CS_N<2>
  VSS37  = GND
  \lbd||rsp_a_n\  = M_C_CPU1_SA_RSP<1>
  \lbs||rsp_b_n\  = M_C_CPU1_SB_RSP<1>
  VSS38  = GND
  CB4_B  = M_C_CPU1_SB_CB<4>
  VSS39  = GND
  CB5_B  = M_C_CPU1_SB_CB<5>
  VSS40  = GND
  \dqs9_b_t||tdqs9_b_t||dbi4_b_n\  = M_C_CPU1_SB_DQS_DP<9>
  \dqs9_b_c||tdqs9_b_c\  = M_C_CPU1_SB_DQS_DN<9>
  VSS41  = GND
  CB0_B  = M_C_CPU1_SB_CB<0>
  VSS42  = GND
  CB1_B  = M_C_CPU1_SB_CB<1>
  VSS43  = GND
  DQ0_B  = M_C_CPU1_SB_DQ<0>
  VSS44  = GND
  DQ1_B  = M_C_CPU1_SB_DQ<1>
  VSS45  = GND
  DQS0_B_T  = M_C_CPU1_SB_DQS_DP<0>
  DQS0_B_C  = M_C_CPU1_SB_DQS_DN<0>
  VSS46  = GND
  DQ4_B  = M_C_CPU1_SB_DQ<4>
  VSS47  = GND
  DQ5_B  = M_C_CPU1_SB_DQ<5>
  VSS48  = GND
  DQ8_B  = M_C_CPU1_SB_DQ<8>
  VSS49  = GND
  DQ9_B  = M_C_CPU1_SB_DQ<9>
  VSS50  = GND
  DQS1_B_T  = M_C_CPU1_SB_DQS_DP<1>
  DQS1_B_C  = M_C_CPU1_SB_DQS_DN<1>
  VSS51  = GND
  DQ12_B  = M_C_CPU1_SB_DQ<12>
  VSS52  = GND
  DQ13_B  = M_C_CPU1_SB_DQ<13>
  VSS53  = GND
  DQ16_B  = M_C_CPU1_SB_DQ<16>
  VSS54  = GND
  DQ17_B  = M_C_CPU1_SB_DQ<17>
  VSS55  = GND
  DQS2_B_T  = M_C_CPU1_SB_DQS_DP<2>
  DQS2_B_C  = M_C_CPU1_SB_DQS_DN<2>
  VSS56  = GND
  DQ20_B  = M_C_CPU1_SB_DQ<20>
  VSS57  = GND
  DQ21_B  = M_C_CPU1_SB_DQ<21>
  VSS58  = GND
  DQ24_B  = M_C_CPU1_SB_DQ<24>
  VSS59  = GND
  DQ25_B  = M_C_CPU1_SB_DQ<25>
  VSS60  = GND
  DQS3_B_T  = M_C_CPU1_SB_DQS_DP<3>
  DQS3_B_C  = M_C_CPU1_SB_DQS_DN<3>
  VSS61  = GND
  DQ28_B  = M_C_CPU1_SB_DQ<28>
  VSS62  = GND
  DQ29_B  = M_C_CPU1_SB_DQ<29>
  VSS63  = GND
  RFU1  = TP_CHC_CPU1_DIMM2_FRU_1
  VIN_BULK1  = P12V_S3_AUX_CPU1_NVDIMM
  VIN_BULK2  = P12V_S3_AUX_CPU1_NVDIMM
  \pwr_good||fail_n\  = PWRGD_CHC_CPU1_DIMM2
  HSA  = PD_CHC_CPU1_DIMM2_SAA
  RFU2  = TP_CHC_CPU1_DIMM2_FRU_2
  RFU3  = TP_CHC_CPU1_DIMM2_FRU_3
  VSS64  = GND
  DQ2_A  = M_C_CPU1_SA_DQ<2>
  VSS65  = GND
  DQ3_A  = M_C_CPU1_SA_DQ<3>
  VSS66  = GND
  \dqs5_a_c||tdqs5_a_c||dqs5_a_t||tdqs5_a_t\  = M_C_CPU1_SA_DQS_DN<5>
  \dqs5_a_t||tdqs5_a_t\  = M_C_CPU1_SA_DQS_DP<5>
  VSS67  = GND
  DQ6_A  = M_C_CPU1_SA_DQ<6>
  VSS68  = GND
  DQ7_A  = M_C_CPU1_SA_DQ<7>
  VSS69  = GND
  DQ10_A  = M_C_CPU1_SA_DQ<10>
  VSS70  = GND
  DQ11_A  = M_C_CPU1_SA_DQ<11>
  VSS71  = GND
  \dqs6_a_c||tdqs6_a_c||dqs6_a_t||tdqs6_a_t\  = M_C_CPU1_SA_DQS_DN<6>
  \dqs6_a_t||tdqs6_a_t\  = M_C_CPU1_SA_DQS_DP<6>
  VSS72  = GND
  DQ14_A  = M_C_CPU1_SA_DQ<14>
  VSS73  = GND
  DQ15_A  = M_C_CPU1_SA_DQ<15>
  VSS74  = GND
  DQ18_A  = M_C_CPU1_SA_DQ<18>
  VSS75  = GND
  DQ19_A  = M_C_CPU1_SA_DQ<19>
  VSS76  = GND
  \dqs7_a_c||tdqs7_a_c\  = M_C_CPU1_SA_DQS_DN<7>
  \dqs7_a_t||tdqs7_a_t\  = M_C_CPU1_SA_DQS_DP<7>
  VSS77  = GND
  DQ22_A  = M_C_CPU1_SA_DQ<22>
  VSS78  = GND
  DQ23_A  = M_C_CPU1_SA_DQ<23>
  VSS79  = GND
  DQ26_A  = M_C_CPU1_SA_DQ<26>
  VSS80  = GND
  DQ27_A  = M_C_CPU1_SA_DQ<27>
  VSS81  = GND
  \dqs8_a_c||tdqs8_a_c\  = M_C_CPU1_SA_DQS_DN<8>
  \dqs8_a_t||tdqs8_a_t\  = M_C_CPU1_SA_DQS_DP<8>
  VSS82  = GND
  DQ30_A  = M_C_CPU1_SA_DQ<30>
  VSS83  = GND
  DQ31_A  = M_C_CPU1_SA_DQ<31>
  VSS84  = GND
  CB2_A  = M_C_CPU1_SA_CB<2>
  VSS85  = GND
  CB3_A  = M_C_CPU1_SA_CB<3>
  VSS86  = GND
  \dqs9_a_c||tdqs9_a_c\  = M_C_CPU1_SA_DQS_DN<9>
  \dqs9_a_t||tdqs9_a_t\  = M_C_CPU1_SA_DQS_DP<9>
  VSS87  = GND
  CB6_A  = M_C_CPU1_SA_CB<6>
  VSS88  = GND
  CB7_A  = M_C_CPU1_SA_CB<7>
  VSS89  = GND
  RESET_N  = RST_M_CD_CPU1_FPGA_N
  VSS90  = GND
  CS1_A_N  = M_C_CPU1_SA_CS_N<3>
  VSS91  = GND
  CA1_A  = M_C_CPU1_SA_CA<1>
  VSS92  = GND
  CA3_A  = M_C_CPU1_SA_CA<3>
  VSS93  = GND
  CA5_A  = M_C_CPU1_SA_CA<5>
  VSS94  = GND
  CK_T  = M_C_CPU1_CLK_DP<1>
  CK_C  = M_C_CPU1_CLK_DN<1>
  VSS95  = GND
  RFU4  = TP_CHC_CPU1_DIMM2_FRU_4
  CA1_B  = M_C_CPU1_SB_CA<1>
  VSS96  = GND
  CA3_B  = M_C_CPU1_SB_CA<3>
  VSS97  = GND
  CA5_B  = M_C_CPU1_SB_CA<5>
  VSS98  = GND
  PAR_B  = M_C_CPU1_SB_PAR
  VSS99  = GND
  CS1_B_N  = M_C_CPU1_SB_CS_N<3>
  VSS100  = GND
  RFU5  = TP_CHC_CPU1_DIMM2_FRU_5
  RFU6  = TP_CHC_CPU1_DIMM2_FRU_6
  VSS101  = GND
  CB6_B  = M_C_CPU1_SB_CB<6>
  VSS102  = GND
  CB7_B  = M_C_CPU1_SB_CB<7>
  VSS103  = GND
  DQS4_B_C  = M_C_CPU1_SB_DQS_DN<4>
  DQS4_B_T  = M_C_CPU1_SB_DQS_DP<4>
  VSS104  = GND
  CB2_B  = M_C_CPU1_SB_CB<2>
  VSS105  = GND
  CB3_B  = M_C_CPU1_SB_CB<3>
  VSS106  = GND
  DQ2_B  = M_C_CPU1_SB_DQ<2>
  VSS107  = GND
  DQ3_B  = M_C_CPU1_SB_DQ<3>
  VSS108  = GND
  \dqs5_b_c||tdqs5_b_c\  = M_C_CPU1_SB_DQS_DN<5>
  \dqs5_b_t||tdqs5_b_t\  = M_C_CPU1_SB_DQS_DP<5>
  VSS109  = GND
  DQ6_B  = M_C_CPU1_SB_DQ<6>
  VSS110  = GND
  DQ7_B  = M_C_CPU1_SB_DQ<7>
  VSS111  = GND
  DQ10_B  = M_C_CPU1_SB_DQ<10>
  VSS112  = GND
  DQ11_B  = M_C_CPU1_SB_DQ<11>
  VSS113  = GND
  \dqs6_b_c||tdqs6_b_c\  = M_C_CPU1_SB_DQS_DN<6>
  \dqs6_b_t||tdqs6_b_t\  = M_C_CPU1_SB_DQS_DP<6>
  VSS114  = GND
  DQ14_B  = M_C_CPU1_SB_DQ<14>
  VSS115  = GND
  DQ15_B  = M_C_CPU1_SB_DQ<15>
  VSS116  = GND
  DQ18_B  = M_C_CPU1_SB_DQ<18>
  VSS117  = GND
  DQ19_B  = M_C_CPU1_SB_DQ<19>
  VSS118  = GND
  \dqs7_b_c||tdqs7_b_c\  = M_C_CPU1_SB_DQS_DN<7>
  \dqs7_b_t||tdqs7_b_t\  = M_C_CPU1_SB_DQS_DP<7>
  VSS119  = GND
  DQ22_B  = M_C_CPU1_SB_DQ<22>
  VSS120  = GND
  DQ23_B  = M_C_CPU1_SB_DQ<23>
  VSS121  = GND
  DQ26_B  = M_C_CPU1_SB_DQ<26>
  VSS122  = GND
  DQ27_B  = M_C_CPU1_SB_DQ<27>
  VSS123  = GND
  \dqs8_b_c||tdqs8_b_c\  = M_C_CPU1_SB_DQS_DN<8>
  \dqs8_b_t||tdqs8_b_t\  = M_C_CPU1_SB_DQS_DP<8>
  VSS124  = GND
  DQ30_B  = M_C_CPU1_SB_DQ<30>
  VSS125  = GND
  DQ31_B  = M_C_CPU1_SB_DQ<31>
  VSS126  = GND
  G1  = GND
  G2  = GND
  G3  = GND

(kicad_pcb
	(version 20260206)
	(generator "pcbnew")
	(generator_version "10.0")
	(general
		(thickness 1.6)
		(legacy_teardrops no)
	)
	(paper "A4")
	(title_block
		(title "03242023_DA0F0TMBIJ0_F0T_Motherboard_J_brd_V01_OCP.brd")
		(comment 1 "Grand Teton / footprint 501 of 6105 (J22), pads 138-182 of 291")
	)
	(layers
		(0 "F.Cu" signal "TOP")
		(4 "In1.Cu" signal "GND")
		(6 "In2.Cu" signal "IN1")
		(8 "In3.Cu" signal "GND1")
		(10 "In4.Cu" signal "IN2")
		(12 "In5.Cu" signal "GND2")
		(14 "In6.Cu" signal "IN3")
		(16 "In7.Cu" signal "GND3")
		(18 "In8.Cu" signal "VCC")
		(20 "In9.Cu" signal "VCC1")
		(22 "In10.Cu" signal "GND4")
		(24 "In11.Cu" signal "IN4")
		(26 "In12.Cu" signal "GND5")
		(28 "In13.Cu" signal "IN5")
		(30 "In14.Cu" signal "GND6")
		(32 "In15.Cu" signal "IN6")
		(34 "In16.Cu" signal "GND7")
		(2 "B.Cu" signal "BOTTOM")
		(9 "F.Adhes" user "F.Adhesive")
		(11 "B.Adhes" user "B.Adhesive")
		(13 "F.Paste" user "Package Geometry/Pastemask Top")
		(15 "B.Paste" user "Package Geometry/Pastemask Bottom")
		(5 "F.SilkS" user "Ref Des/Silkscreen Top")
		(7 "B.SilkS" user "Ref Des/Silkscreen Bottom")
		(1 "F.Mask" user "Board Geometry/Soldermask Top")
		(3 "B.Mask" user "Board Geometry/Soldermask Bottom")
		(17 "Dwgs.User" user "User.Drawings")
		(19 "Cmts.User" user "User.Comments")
		(21 "Eco1.User" user "User.Eco1")
		(23 "Eco2.User" user "User.Eco2")
		(25 "Edge.Cuts" user "Board Geometry/Outline")
		(27 "Margin" user)
		(31 "F.CrtYd" user "Package Geometry/Place Bound Top")
		(29 "B.CrtYd" user "Package Geometry/Place Bound Bottom")
		(35 "F.Fab" user "Ref Des/Assembly Top")
		(33 "B.Fab" user "Ref Des/Assembly Bottom")
	)
	(footprint ""
		(layer "F.Cu")
		(at 32.82188 -258.091686)
		(property "Reference" "J22"
			(at -1.420622 -81.912714 0)
			(unlocked yes)
			(layer "F.SilkS")
			(effects
				(font
					(size 0.7874 0.5842)
					(thickness 0.1524)
				)
				(justify left)
			)
		)
		(property "Value" ""
			(at 0 0 0)
			(layer "F.Fab")
			(effects
				(font
					(size 1.27 1.27)
				)
			)
		)
		(duplicate_pad_numbers_are_jumpers no)
		(pad "138" smd rect
			(at -2.050034 58.224928 270)
			(size 0.519938 1.4986)
			(layers "F.Cu" "F.Mask" "F.Paste")
			(net "M_C_CPU1_SB_DQS_DN<3>")
		)
		(pad "139" smd rect
			(at -2.050034 59.075066 270)
			(size 0.519938 1.4986)
			(layers "F.Cu" "F.Mask" "F.Paste")
			(net "GND")
		)
		(pad "140" smd rect
			(at -2.050034 59.92495 270)
			(size 0.519938 1.4986)
			(layers "F.Cu" "F.Mask" "F.Paste")
			(net "M_C_CPU1_SB_DQ<28>")
		)
		(pad "141" smd rect
			(at -2.050034 60.775088 270)
			(size 0.519938 1.4986)
			(layers "F.Cu" "F.Mask" "F.Paste")
			(net "GND")
		)
		(pad "142" smd rect
			(at -2.050034 61.624972 270)
			(size 0.519938 1.4986)
			(layers "F.Cu" "F.Mask" "F.Paste")
			(net "M_C_CPU1_SB_DQ<29>")
		)
		(pad "143" smd rect
			(at -2.050034 62.47511 270)
			(size 0.519938 1.4986)
			(layers "F.Cu" "F.Mask" "F.Paste")
			(net "GND")
		)
		(pad "144" smd rect
			(at -2.050034 63.324994 270)
			(size 0.519938 1.4986)
			(layers "F.Cu" "F.Mask" "F.Paste")
			(net "TP_CHC_CPU1_DIMM2_FRU_1")
		)
		(pad "145" smd rect
			(at 2.050034 -63.324994 270)
			(size 0.519938 1.4986)
			(layers "F.Cu" "F.Mask" "F.Paste")
			(net "P12V_S3_AUX_CPU1_NVDIMM")
		)
		(pad "146" smd rect
			(at 2.050034 -62.47511 270)
			(size 0.519938 1.4986)
			(layers "F.Cu" "F.Mask" "F.Paste")
			(net "P12V_S3_AUX_CPU1_NVDIMM")
		)
		(pad "147" smd rect
			(at 2.050034 -61.624972 270)
			(size 0.519938 1.4986)
			(layers "F.Cu" "F.Mask" "F.Paste")
			(net "PWRGD_CHC_CPU1_DIMM2")
		)
		(pad "148" smd rect
			(at 2.050034 -60.775088 270)
			(size 0.519938 1.4986)
			(layers "F.Cu" "F.Mask" "F.Paste")
			(net "PD_CHC_CPU1_DIMM2_SAA")
		)
		(pad "149" smd rect
			(at 2.050034 -59.92495 270)
			(size 0.519938 1.4986)
			(layers "F.Cu" "F.Mask" "F.Paste")
			(net "TP_CHC_CPU1_DIMM2_FRU_2")
		)
		(pad "150" smd rect
			(at 2.050034 -59.075066 270)
			(size 0.519938 1.4986)
			(layers "F.Cu" "F.Mask" "F.Paste")
			(net "TP_CHC_CPU1_DIMM2_FRU_3")
		)
		(pad "151" smd rect
			(at 2.050034 -58.224928 270)
			(size 0.519938 1.4986)
			(layers "F.Cu" "F.Mask" "F.Paste")
			(net "GND")
		)
		(pad "152" smd rect
			(at 2.050034 -57.375044 270)
			(size 0.519938 1.4986)
			(layers "F.Cu" "F.Mask" "F.Paste")
			(net "M_C_CPU1_SA_DQ<2>")
		)
		(pad "153" smd rect
			(at 2.050034 -56.524906 270)
			(size 0.519938 1.4986)
			(layers "F.Cu" "F.Mask" "F.Paste")
			(net "GND")
		)
		(pad "154" smd rect
			(at 2.050034 -55.675022 270)
			(size 0.519938 1.4986)
			(layers "F.Cu" "F.Mask" "F.Paste")
			(net "M_C_CPU1_SA_DQ<3>")
		)
		(pad "155" smd rect
			(at 2.050034 -54.824884 270)
			(size 0.519938 1.4986)
			(layers "F.Cu" "F.Mask" "F.Paste")
			(net "GND")
		)
		(pad "156" smd rect
			(at 2.050034 -53.975 270)
			(size 0.519938 1.4986)
			(layers "F.Cu" "F.Mask" "F.Paste")
			(net "M_C_CPU1_SA_DQS_DN<5>")
		)
		(pad "157" smd rect
			(at 2.050034 -53.125116 270)
			(size 0.519938 1.4986)
			(layers "F.Cu" "F.Mask" "F.Paste")
			(net "M_C_CPU1_SA_DQS_DP<5>")
		)
		(pad "158" smd rect
			(at 2.050034 -52.274978 270)
			(size 0.519938 1.4986)
			(layers "F.Cu" "F.Mask" "F.Paste")
			(net "GND")
		)
		(pad "159" smd rect
			(at 2.050034 -51.425094 270)
			(size 0.519938 1.4986)
			(layers "F.Cu" "F.Mask" "F.Paste")
			(net "M_C_CPU1_SA_DQ<6>")
		)
		(pad "160" smd rect
			(at 2.050034 -50.574956 270)
			(size 0.519938 1.4986)
			(layers "F.Cu" "F.Mask" "F.Paste")
			(net "GND")
		)
		(pad "161" smd rect
			(at 2.050034 -49.725072 270)
			(size 0.519938 1.4986)
			(layers "F.Cu" "F.Mask" "F.Paste")
			(net "M_C_CPU1_SA_DQ<7>")
		)
		(pad "162" smd rect
			(at 2.050034 -48.874934 270)
			(size 0.519938 1.4986)
			(layers "F.Cu" "F.Mask" "F.Paste")
			(net "GND")
		)
		(pad "163" smd rect
			(at 2.050034 -48.02505 270)
			(size 0.519938 1.4986)
			(layers "F.Cu" "F.Mask" "F.Paste")
			(net "M_C_CPU1_SA_DQ<10>")
		)
		(pad "164" smd rect
			(at 2.050034 -47.174912 270)
			(size 0.519938 1.4986)
			(layers "F.Cu" "F.Mask" "F.Paste")
			(net "GND")
		)
		(pad "165" smd rect
			(at 2.050034 -46.325028 270)
			(size 0.519938 1.4986)
			(layers "F.Cu" "F.Mask" "F.Paste")
			(net "M_C_CPU1_SA_DQ<11>")
		)
		(pad "166" smd rect
			(at 2.050034 -45.47489 270)
			(size 0.519938 1.4986)
			(layers "F.Cu" "F.Mask" "F.Paste")
			(net "GND")
		)
		(pad "167" smd rect
			(at 2.050034 -44.625006 270)
			(size 0.519938 1.4986)
			(layers "F.Cu" "F.Mask" "F.Paste")
			(net "M_C_CPU1_SA_DQS_DN<6>")
		)
		(pad "168" smd rect
			(at 2.050034 -43.775122 270)
			(size 0.519938 1.4986)
			(layers "F.Cu" "F.Mask" "F.Paste")
			(net "M_C_CPU1_SA_DQS_DP<6>")
		)
		(pad "169" smd rect
			(at 2.050034 -42.924984 270)
			(size 0.519938 1.4986)
			(layers "F.Cu" "F.Mask" "F.Paste")
			(net "GND")
		)
		(pad "170" smd rect
			(at 2.050034 -42.0751 270)
			(size 0.519938 1.4986)
			(layers "F.Cu" "F.Mask" "F.Paste")
			(net "M_C_CPU1_SA_DQ<14>")
		)
		(pad "171" smd rect
			(at 2.050034 -41.224962 270)
			(size 0.519938 1.4986)
			(layers "F.Cu" "F.Mask" "F.Paste")
			(net "GND")
		)
		(pad "172" smd rect
			(at 2.050034 -40.375078 270)
			(size 0.519938 1.4986)
			(layers "F.Cu" "F.Mask" "F.Paste")
			(net "M_C_CPU1_SA_DQ<15>")
		)
		(pad "173" smd rect
			(at 2.050034 -39.52494 270)
			(size 0.519938 1.4986)
			(layers "F.Cu" "F.Mask" "F.Paste")
			(net "GND")
		)
		(pad "174" smd rect
			(at 2.050034 -38.675056 270)
			(size 0.519938 1.4986)
			(layers "F.Cu" "F.Mask" "F.Paste")
			(net "M_C_CPU1_SA_DQ<18>")
		)
		(pad "175" smd rect
			(at 2.050034 -37.824918 270)
			(size 0.519938 1.4986)
			(layers "F.Cu" "F.Mask" "F.Paste")
			(net "GND")
		)
		(pad "176" smd rect
			(at 2.050034 -36.975034 270)
			(size 0.519938 1.4986)
			(layers "F.Cu" "F.Mask" "F.Paste")
			(net "M_C_CPU1_SA_DQ<19>")
		)
		(pad "177" smd rect
			(at 2.050034 -36.124896 270)
			(size 0.519938 1.4986)
			(layers "F.Cu" "F.Mask" "F.Paste")
			(net "GND")
		)
		(pad "178" smd rect
			(at 2.050034 -35.275012 270)
			(size 0.519938 1.4986)
			(layers "F.Cu" "F.Mask" "F.Paste")
			(net "M_C_CPU1_SA_DQS_DN<7>")
		)
		(pad "179" smd rect
			(at 2.050034 -34.425128 270)
			(size 0.519938 1.4986)
			(layers "F.Cu" "F.Mask" "F.Paste")
			(net "M_C_CPU1_SA_DQS_DP<7>")
		)
		(pad "180" smd rect
			(at 2.050034 -33.57499 270)
			(size 0.519938 1.4986)
			(layers "F.Cu" "F.Mask" "F.Paste")
			(net "GND")
		)
		(pad "181" smd rect
			(at 2.050034 -32.725106 270)
			(size 0.519938 1.4986)
			(layers "F.Cu" "F.Mask" "F.Paste")
			(net "M_C_CPU1_SA_DQ<22>")
		)
		(pad "182" smd rect
			(at 2.050034 -31.874968 270)
			(size 0.519938 1.4986)
			(layers "F.Cu" "F.Mask" "F.Paste")
			(net "GND")
		)
	)
)
